FILE_TYPE = CONNECTIVITY;
{Allegro Design Entry HDL 17.2-2016 S081 (4005846) 1/11/2022}
"PAGE_NUMBER" = 326;
0"NC";
1"P3V3_AUX\g";
2"P12V_AUX\g";
3"P12V_AUX\g";
4"P3V3_AUX\g";
5"P3V3_AUX\g";
6"P3V3_AUX\g";
7"P3V3_AUX\g";
8"P3V3_AUX\g";
9"P3V3_AUX\g";
10"P12V_AUX\g";
11"P12V_AUX\g";
12"GND\g";
13"GND\g";
14"GND\g";
15"GND\g";
16"GND\g";
17"GND\g";
18"GND\g";
19"GND\g";
20"GND\g";
21"GND\g";
22"GND\g";
23"GND\g";
24"GND\g";
25"GND\g";
26"GND\g";
27"GND\g";
28"GND\g";
29"GND\g";
30"GND\g";
31"GND\g";
32"P12V_AUX\g";
33"GND\g";
34"OC_P2V5_COMP";
35"U206_VDD";
36"HSC_CSOUT";
37"HSC_OC_VOL";
38"HSC_D_OC_R2";
39"A_P12V_STBY_FP_TRIGGER";
40"A_P12V_STBY_ADR_TRIGGER";
41"U205_VDD";
42"A_HSC_INAP";
43"NC_U205_INB-";
44"FM_UV_ADR_TRIGGER_N";
45"A_P12V_STBY_FPH_GATE";
46"IRQ_UV_DETECT_N";
47"HSC_CSOUT";
48"A_HSC_HIGH";
49"A_HSC_LOW";
50"PWRGD_DSW_PWROK_R4";
51"U369_VDD";
52"A_HSC_LOW_DRAIN";
53"PWRGD_DSW_PWROK";
54"A_HSC_LOW_GATE";
55"A_HSC_LOW_GATE";
56"HSC_D_OC";
57"NC_U205_OUTB";
%"UNIVERSAL_GND"
"1","(-2575,-1525)","0","logical_power","I1";
;
CDS_LIB"logical_power"
HDL_POWER"GND";
"A"26;
%"Q_RES"
"2","(-525,275)","0","pure_quanta","I100";
;
PART_NUMBER"CS32672FB03"
PACK_TYPE"0402LF"
VALUE"26.7K"
TOLERANCE"1%"
WATTAGE"1/16W"
MATERIAL"CHIP"
LOCATION"R2219"
CDS_LIB"pure_quanta"
$SEC"1"
CDS_SEC"1";
"A"
$PN"1"10;
"B"
$PN"2"40;
%"Q_RES"
"2","(-525,-475)","0","pure_quanta","I101";
;
PART_NUMBER"CS21002FB06"
PACK_TYPE"0402LF"
VALUE"1K"
TOLERANCE"1%"
MATERIAL"CHIP"
WATTAGE"1/16W"
LOCATION"R2227"
CDS_LIB"pure_quanta"
$SEC"1"
CDS_SEC"1";
"A"
$PN"1"40;
"B"
$PN"2"24;
%"LT6700CS61TRPBF"
"1","(1850,-175)","0","pure_quanta","I102";
;
PART_NUMBER"AL006700001"
MATERIAL"IC"
VALUE"LT6700CS6-1#TRPBF"
PART_TYPE"SMLF"
LOCATION"U206"
CDS_LMAN_SYM_OUTLINE"-225,150,225,-150"
NEEDS_NO_SIZE"TRUE"
CDS_LIB"pure_quanta"
$SEC"1"
CDS_SEC"1";
"OUTB"
$PN"6"45;
"INA+"
$PN"3"40;
"OUTA"
$PN"1"44;
"GND"
$PN"2"22;
"INB-"
$PN"4"39;
"VS"
$PN"5"35;
%"UNIVERSAL_POWER"
"1","(-525,625)","0","logical_power","I12";
;
HDL_POWER"P12V_AUX"
CDS_LIB"logical_power";
"A"10;
%"Q_RES"
"2","(-1100,3450)","0","pure_quanta","I13";
;
PART_NUMBER"CS31002FB08"
PACK_TYPE"0402LF"
WATTAGE"1/16W"
VALUE"10K"
TOLERANCE"1%"
MATERIAL"EMPTY"
$LOCATION"R4668"
CDS_LIB"pure_quanta"
CDS_LOCATION"R4668"
$SEC"1"
CDS_SEC"1";
"A"
$PN"1"49;
"B"
$PN"2"20;
%"Q_RES"
"2","(-1100,4050)","0","pure_quanta","I14";
;
PART_NUMBER"CS41602FB05"
PACK_TYPE"0402LF"
WATTAGE"1/16W"
VALUE"160K"
TOLERANCE"1%"
MATERIAL"EMPTY"
$LOCATION"R4667"
CDS_LIB"pure_quanta"
CDS_LOCATION"R4667"
$SEC"1"
CDS_SEC"1";
"A"
$PN"1"47;
"B"
$PN"2"49;
%"UNIVERSAL_GND"
"1","(75,-775)","0","logical_power","I15";
;
HDL_POWER"GND"
CDS_LIB"logical_power";
"A"23;
%"Q_RES"
"2","(75,-475)","0","pure_quanta","I17";
;
PART_NUMBER"CS21002FB06"
WATTAGE"1/16W"
VALUE"1K"
TOLERANCE"1%"
MATERIAL"CHIP"
PACK_TYPE"0402LF"
LOCATION"R2222"
CDS_LIB"pure_quanta"
$SEC"1"
CDS_SEC"1";
"A"
$PN"1"39;
"B"
$PN"2"23;
%"UNIVERSAL_GND"
"1","(550,25)","0","logical_power","I18";
;
HDL_POWER"GND"
CDS_LIB"logical_power";
"A"28;
%"Q_RES"
"2","(-2575,-1275)","0","pure_quanta","I2";
;
PART_NUMBER"CS24992FB07"
VALUE"4.99K"
TOLERANCE"1%"
WATTAGE"1/16W"
MATERIAL"EMPTY"
PACK_TYPE"0402LF"
$LOCATION"R2238"
CDS_LIB"pure_quanta"
CDS_LOCATION"R2238"
$SEC"1"
CDS_SEC"1";
"A"
$PN"1"42;
"B"
$PN"2"26;
%"Q_RES"
"2","(75,275)","0","pure_quanta","I20";
;
PART_NUMBER"CS32672FB03"
WATTAGE"1/16W"
TOLERANCE"1%"
VALUE"26.7K"
MATERIAL"CHIP"
PACK_TYPE"0402LF"
LOCATION"R2221"
CDS_LIB"pure_quanta"
$SEC"1"
CDS_SEC"1";
"A"
$PN"1"3;
"B"
$PN"2"39;
%"UNIVERSAL_POWER"
"1","(75,625)","0","logical_power","I21";
;
HDL_POWER"P12V_AUX"
CDS_LIB"logical_power";
"A"3;
%"UNIVERSAL_GND"
"1","(-550,3100)","0","logical_power","I23";
;
HDL_POWER"GND"
CDS_LIB"logical_power";
"A"20;
%"Q_RES"
"2","(-550,3450)","0","pure_quanta","I24";
;
PART_NUMBER"CS31002FB08"
TOLERANCE"1%"
MATERIAL"EMPTY"
VALUE"10K"
WATTAGE"1/16W"
PACK_TYPE"0402LF"
$LOCATION"R4670"
CDS_LIB"pure_quanta"
CDS_LOCATION"R4670"
$SEC"1"
CDS_SEC"1";
"A"
$PN"1"48;
"B"
$PN"2"20;
%"Q_RES"
"2","(-550,4050)","0","pure_quanta","I25";
;
PART_NUMBER"CS41602FB05"
VALUE"160K"
PACK_TYPE"0402LF"
WATTAGE"1/16W"
MATERIAL"EMPTY"
TOLERANCE"1%"
$LOCATION"R4669"
CDS_LIB"pure_quanta"
CDS_LOCATION"R4669"
$SEC"1"
CDS_SEC"1";
"A"
$PN"1"47;
"B"
$PN"2"48;
%"UNIVERSAL_GND"
"1","(0,3800)","0","logical_power","I26";
;
HDL_POWER"GND"
CDS_LIB"logical_power";
"A"27;
%"Q_RES"
"1","(1000,3050)","0","pure_quanta","I29";
;
PART_NUMBER"CS00002JB13"
ROOM"HSC1_BOM2"
WATTAGE"1/16W"
PACK_TYPE"0402LF"
MATERIAL"EMPTY"
TOLERANCE"5%"
VALUE"0"
$LOCATION"R4693"
CDS_LIB"pure_quanta"
CDS_LOCATION"R4693"
$SEC"1"
CDS_SEC"1";
"B"
$PN"2"56;
"A"
$PN"1"47;
%"UNIVERSAL_GND"
"1","(-2025,-1275)","0","logical_power","I3";
;
HDL_POWER"GND"
CDS_LIB"logical_power";
"A"30;
%"TPS3700DDCR"
"1","(1075,3700)","0","pure_quanta","I30";
;
PART_NUMBER"AL003700002"
VALUE"TPS3700DDCR"
PART_TYPE"SMLF"
MATERIAL"EMPTY"
LOCATION"U369"
CDS_LIB"pure_quanta"
NEEDS_NO_SIZE"TRUE"
CDS_LMAN_SYM_OUTLINE"-225,150,225,-150"
$SEC"1"
CDS_SEC"1";
"OUTB"
$PN"6"56;
"INA+"
$PN"3"49;
"OUTA"
$PN"1"55;
"GND"
$PN"2"19;
"INB-"
$PN"4"48;
"VDD"
$PN"5"51;
%"Q_RES"
"1","(925,-1375)","0","pure_quanta","I33";
;
PART_NUMBER"CS00002JB13"
PACK_TYPE"0402LF"
MATERIAL"EMPTY"
WATTAGE"1/16W"
VALUE"0"
TOLERANCE"5%"
LOCATION"R2330"
CDS_LIB"pure_quanta"
$SEC"1"
CDS_SEC"1";
"B"
$PN"2"53;
"A"
$PN"1"50;
%"UNIVERSAL_GND"
"1","(2300,-450)","0","logical_power","I35";
;
HDL_POWER"GND"
CDS_LIB"logical_power";
"A"22;
%"UNIVERSAL_GND"
"1","(4050,-500)","0","logical_power","I37";
;
HDL_POWER"GND"
CDS_LIB"logical_power";
"A"21;
%"MOSFET_N"
"1","(4000,-125)","0","pure_quanta","I38";
;
PART_NUMBER"BAM138K0000"
MATERIAL"IC"
MANUF_PN"BSS138K"
VALUE"BSS138K"
$LOCATION"U325"
PACK_TYPE"SMLF"
CDS_LIB"pure_quanta"
CDS_LMAN_SYM_OUTLINE"-50,50,100,-150"
CDS_LOCATION"U325"
$SEC"1"
CDS_SEC"1";
"GATE"
$PN"G"45;
"SOURCE"
$PN"S"21;
"DRAIN"
$PN"D"46;
%"Q_RES"
"2","(2400,250)","0","pure_quanta","I39";
;
PART_NUMBER"CS31002FB08"
VALUE"10K"
TOLERANCE"1%"
WATTAGE"1/16W"
MATERIAL"CHIP"
PACK_TYPE"0402LF"
LOCATION"R2230"
CDS_LIB"pure_quanta"
$SEC"1"
CDS_SEC"1";
"A"
$PN"1"5;
"B"
$PN"2"45;
%"UNIVERSAL_POWER"
"1","(2400,625)","0","logical_power","I40";
;
HDL_POWER"P3V3_AUX"
CDS_LIB"logical_power";
"A"5;
%"Q_RES"
"2","(2675,250)","0","pure_quanta","I41";
;
PART_NUMBER"CS31002FB08"
TOLERANCE"1%"
WATTAGE"1/16W"
MATERIAL"CHIP"
VALUE"10K"
PACK_TYPE"0402LF"
LOCATION"R2233"
CDS_LIB"pure_quanta"
$SEC"1"
CDS_SEC"1";
"A"
$PN"1"5;
"B"
$PN"2"44;
%"UNIVERSAL_GND"
"1","(1525,3475)","0","logical_power","I42";
;
HDL_POWER"GND"
CDS_LIB"logical_power";
"A"19;
%"UNIVERSAL_GND"
"1","(1975,3175)","0","logical_power","I43";
;
CDS_LIB"logical_power"
HDL_POWER"GND";
"A"18;
%"Q_RES"
"2","(1975,3400)","0","pure_quanta","I44";
;
PART_NUMBER"CS00002JB13"
TOLERANCE"5%"
PACK_TYPE"0402LF"
MATERIAL"EMPTY"
WATTAGE"1/16W"
VALUE"0"
$LOCATION"R4673"
CDS_LIB"pure_quanta"
CDS_LOCATION"R4673"
$SEC"1"
CDS_SEC"1";
"A"
$PN"1"55;
"B"
$PN"2"18;
%"Q_RES"
"2","(4050,450)","0","pure_quanta","I45";
;
PART_NUMBER"CS24702JB10"
VALUE"4.7K"
TOLERANCE"5%"
WATTAGE"1/16W"
MATERIAL"CHIP"
PACK_TYPE"0402LF"
$LOCATION"R4620"
CDS_LIB"pure_quanta"
CDS_LOCATION"R4620"
$SEC"1"
CDS_SEC"1";
"A"
$PN"1"1;
"B"
$PN"2"46;
%"MOSFET_NCH_GDS_ESD_PROTECTED"
"1","(2825,4100)","0","pure_quanta","I46";
;
PART_NUMBER"BAM70020002"
PART_TYPE"SMLF"
VALUE"2N7002K"
MATERIAL"EMPTY"
$LOCATION"U329"
CDS_LIB"pure_quanta"
CDS_LMAN_SYM_OUTLINE"-125,150,125,-150"
NEEDS_NO_SIZE"TRUE"
CDS_LOCATION"U329"
$SEC"1"
CDS_SEC"1";
"S"
$PN"S"17;
"G"
$PN"G"55;
"D"
$PN"D"52;
%"UNIVERSAL_GND"
"1","(2850,3775)","0","logical_power","I47";
;
CDS_LIB"logical_power"
HDL_POWER"GND";
"A"17;
%"Q_RES"
"2","(3575,3975)","0","pure_quanta","I48";
;
PART_NUMBER"CS00002JB13"
MATERIAL"EMPTY"
WATTAGE"1/16W"
PACK_TYPE"0402LF"
VALUE"0"
TOLERANCE"5%"
LOCATION"R4652"
CDS_LIB"pure_quanta"
$SEC"1"
CDS_SEC"1";
"A"
$PN"1"52;
"B"
$PN"2"56;
%"TPS3700DDCR"
"1","(-725,-1425)","0","pure_quanta","I5";
;
PART_NUMBER"AL003700002"
MATERIAL"EMPTY"
VALUE"TPS3700DDCR"
PART_TYPE"SMLF"
$LOCATION"U205"
CDS_LIB"pure_quanta"
NEEDS_NO_SIZE"TRUE"
CDS_LMAN_SYM_OUTLINE"-225,150,225,-150"
CDS_LOCATION"U205"
$SEC"1"
CDS_SEC"1";
"OUTB"
$PN"6"57;
"INA+"
$PN"3"42;
"OUTA"
$PN"1"50;
"GND"
$PN"2"25;
"INB-"
$PN"4"43;
"VDD"
$PN"5"41;
%"Q_RES"
"2","(1675,4125)","0","pure_quanta","I51";
;
PART_NUMBER"CS31002FB08"
PACK_TYPE"0402LF"
TOLERANCE"1%"
VALUE"10K"
MATERIAL"EMPTY"
WATTAGE"1/16W"
$LOCATION"R4671"
CDS_LIB"pure_quanta"
CDS_LOCATION"R4671"
$SEC"1"
CDS_SEC"1";
"A"
$PN"1"8;
"B"
$PN"2"56;
%"UNIVERSAL_POWER"
"1","(1675,4500)","0","logical_power","I52";
;
HDL_POWER"P3V3_AUX"
CDS_LIB"logical_power";
"A"8;
%"Q_RES"
"2","(1950,4125)","0","pure_quanta","I53";
;
PART_NUMBER"CS31002FB08"
PACK_TYPE"0402LF"
MATERIAL"EMPTY"
WATTAGE"1/16W"
TOLERANCE"1%"
VALUE"10K"
$LOCATION"R4672"
CDS_LIB"pure_quanta"
CDS_LOCATION"R4672"
$SEC"1"
CDS_SEC"1";
"A"
$PN"1"8;
"B"
$PN"2"55;
%"UNIVERSAL_POWER"
"1","(4050,725)","0","logical_power","I54";
;
HDL_POWER"P3V3_AUX"
CDS_LIB"logical_power";
"A"1;
%"UNIVERSAL_GND"
"1","(-1250,825)","0","logical_power","I55";
;
HDL_POWER"GND"
CDS_LIB"logical_power";
"A"16;
%"LM4040AIM3X25NOPB"
"1","(-875,1150)","0","pure_quanta","I56";
;
PART_NUMBER"AL404025013"
MATERIAL"EMPTY"
PART_TYPE"SMLF"
VALUE"LM4040AIM3X-2.5/NOPB"
$LOCATION"U343"
CDS_LIB"pure_quanta"
PIN_NAMES_ROTATE"True"
CDS_LMAN_SYM_OUTLINE"-200,250,200,-250"
CDS_LOCATION"U343"
$SEC"1"
CDS_SEC"1";
"3"
$PN"3"0;
"2-"
$PN"2"16;
"1+"
$PN"1"34;
%"Q_RES"
"2","(-1275,1975)","0","pure_quanta","I57";
;
PART_NUMBER"CS31002FB08"
MATERIAL"EMPTY"
WATTAGE"1/16W"
PACK_TYPE"0402LF"
VALUE"10K"
TOLERANCE"1%"
$LOCATION"R4792"
CDS_LIB"pure_quanta"
CDS_LOCATION"R4792"
$SEC"1"
CDS_SEC"1";
"A"
$PN"1"7;
"B"
$PN"2"34;
%"UNIVERSAL_POWER"
"1","(-1275,2300)","0","logical_power","I58";
;
HDL_POWER"P3V3_AUX"
CDS_LIB"logical_power";
"A"7;
%"UNIVERSAL_GND"
"1","(-275,1075)","0","logical_power","I59";
;
HDL_POWER"GND"
CDS_LIB"logical_power";
"A"15;
%"UNIVERSAL_GND"
"1","(-275,-1650)","0","logical_power","I6";
;
HDL_POWER"GND"
CDS_LIB"logical_power";
"A"25;
%"UNIVERSAL_GND"
"1","(125,1075)","0","logical_power","I63";
;
CDS_LIB"logical_power"
HDL_POWER"GND";
"A"14;
%"Q_CAP"
"1","(125,1350)","2","pure_quanta","I64";
;
PART_NUMBER"CH4106K1B01"
MATERIAL"EMPTY"
TOLERANCE"10%"
VOLTAGE"50V"
VALUE"100NF"
PACK_TYPE"C0402"
$LOCATION"C2388"
CDS_LIB"pure_quanta"
CDS_LOCATION"C2388"
$SEC"1"
CDS_SEC"1";
"B"
$PN"2"14;
"A"
$PN"1"34;
%"UNIVERSAL_GND"
"1","(550,1075)","0","logical_power","I65";
;
HDL_POWER"GND"
CDS_LIB"logical_power";
"A"33;
%"AP331AWG7"
"1","(900,1750)","0","pure_quanta","I66";
;
PART_NUMBER"AL000331011"
PART_TYPE"SMLF"
VALUE"AP331AWG-7"
MATERIAL"EMPTY"
$LOCATION"U344"
CDS_LIB"pure_quanta"
NEEDS_NO_SIZE"TRUE"
CDS_LMAN_SYM_OUTLINE"-100,100,100,-100"
CDS_LOCATION"U344"
$SEC"1"
CDS_SEC"1";
"GND"
$PN"2"13;
"VCC"
$PN"5"2;
"OUTPUT"
$PN"4"38;
"IN-"
$PN"1"34;
"IN+"
$PN"3"37;
%"UNIVERSAL_GND"
"1","(900,1325)","0","logical_power","I67";
;
HDL_POWER"GND"
CDS_LIB"logical_power";
"A"13;
%"Q_RES"
"1","(1350,2075)","0","pure_quanta","I68";
;
PART_NUMBER"CS51002FB05"
MATERIAL"EMPTY"
PACK_TYPE"0402LF"
TOLERANCE"1%"
VALUE"1M"
WATTAGE"1/16W"
$LOCATION"R4793"
CDS_LIB"pure_quanta"
CDS_LOCATION"R4793"
$SEC"1"
CDS_SEC"1";
"B"
$PN"2"38;
"A"
$PN"1"37;
%"UNIVERSAL_POWER"
"1","(900,2600)","0","logical_power","I69";
;
HDL_POWER"P12V_AUX"
CDS_LIB"logical_power";
"A"2;
%"Q_RES"
"2","(-2575,-875)","0","pure_quanta","I7";
;
PART_NUMBER"CS41002FB09"
VALUE"100K"
WATTAGE"1/16W"
PACK_TYPE"0402LF"
TOLERANCE"1%"
MATERIAL"EMPTY"
LOCATION"R2236"
CDS_LIB"pure_quanta"
$SEC"1"
CDS_SEC"1";
"A"
$PN"1"11;
"B"
$PN"2"42;
%"UNIVERSAL_GND"
"1","(1150,2175)","0","logical_power","I70";
;
CDS_LIB"logical_power"
HDL_POWER"GND";
"A"12;
%"Q_CAP"
"1","(1150,2375)","2","pure_quanta","I71";
;
PART_NUMBER"CH4106K1B01"
VALUE"100NF"
VOLTAGE"50V"
TOLERANCE"10%"
MATERIAL"EMPTY"
PACK_TYPE"C0402"
$LOCATION"C2390"
CDS_LIB"pure_quanta"
CDS_LOCATION"C2390"
$SEC"1"
CDS_SEC"1";
"B"
$PN"2"12;
"A"
$PN"1"2;
%"Q_RES"
"1","(2275,1750)","0","pure_quanta","I72";
;
PART_NUMBER"CS03322FB03"
TOLERANCE"1%"
VALUE"33.2"
$LOCATION"R4794"
MATERIAL"EMPTY"
PACK_TYPE"0402LF"
WATTAGE"1/16W"
CDS_LIB"pure_quanta"
CDS_LOCATION"R4794"
$SEC"1"
CDS_SEC"1";
"B"
$PN"2"54;
"A"
$PN"1"38;
%"Q_CAP"
"1","(550,1350)","2","pure_quanta","I76";
;
PART_NUMBER"CH4106K1B01"
PACK_TYPE"C0402"
MATERIAL"EMPTY"
TOLERANCE"10%"
VALUE"100NF"
VOLTAGE"50V"
$LOCATION"C2389"
CDS_LIB"pure_quanta"
CDS_LOCATION"C2389"
$SEC"1"
CDS_SEC"1";
"B"
$PN"2"33;
"A"
$PN"1"37;
%"Q_RES"
"2","(-275,1350)","0","pure_quanta","I77";
;
PART_NUMBER"CS31002FB08"
VALUE"10K"
MATERIAL"EMPTY"
PACK_TYPE"0402LF"
WATTAGE"1/16W"
TOLERANCE"1%"
$LOCATION"R4796"
CDS_LIB"pure_quanta"
CDS_LOCATION"R4796"
$SEC"1"
CDS_SEC"1";
"A"
$PN"1"37;
"B"
$PN"2"15;
%"Q_RES"
"2","(-275,2025)","0","pure_quanta","I78";
;
PART_NUMBER"CS41602FB05"
PACK_TYPE"0402LF"
VALUE"160K"
TOLERANCE"1%"
WATTAGE"1/16W"
MATERIAL"EMPTY"
$LOCATION"R4795"
CDS_LIB"pure_quanta"
CDS_LOCATION"R4795"
$SEC"1"
CDS_SEC"1";
"A"
$PN"1"36;
"B"
$PN"2"37;
%"UNIVERSAL_POWER"
"1","(-2575,-625)","0","logical_power","I8";
;
HDL_POWER"P12V_AUX"
CDS_LIB"logical_power";
"A"11;
%"Q_RES"
"2","(3100,2025)","0","pure_quanta","I80";
;
PART_NUMBER"CS31002FB08"
PACK_TYPE"0402LF"
MATERIAL"EMPTY"
TOLERANCE"1%"
WATTAGE"1/16W"
VALUE"10K"
$LOCATION"R4797"
CDS_LIB"pure_quanta"
CDS_LOCATION"R4797"
$SEC"1"
CDS_SEC"1";
"A"
$PN"1"6;
"B"
$PN"2"54;
%"UNIVERSAL_POWER"
"1","(3100,2350)","0","logical_power","I81";
;
HDL_POWER"P3V3_AUX"
CDS_LIB"logical_power";
"A"6;
%"UNIVERSAL_POWER"
"1","(650,4650)","0","logical_power","I84";
;
HDL_POWER"P3V3_AUX"
CDS_LIB"logical_power";
"A"9;
%"UNIVERSAL_POWER"
"1","(1275,900)","0","logical_power","I86";
;
HDL_POWER"P12V_AUX"
CDS_LIB"logical_power";
"A"32;
%"UNIVERSAL_POWER"
"1","(-1300,-425)","0","logical_power","I87";
;
HDL_POWER"P3V3_AUX"
CDS_LIB"logical_power";
"A"4;
%"Q_CAP"
"1","(-2025,-1025)","0","pure_quanta","I89";
;
PART_NUMBER"CH5104KEB02"
TOLERANCE"10%"
MATERIAL"EMPTY"
PACK_TYPE"C0402"
VALUE"1UF"
VOLTAGE"25V"
LOCATION"C1562"
CDS_LIB"pure_quanta"
$SEC"1"
CDS_SEC"1";
"B"
$PN"2"30;
"A"
$PN"1"41;
%"UNIVERSAL_GND"
"1","(-525,-775)","0","logical_power","I9";
;
CDS_LIB"logical_power"
HDL_POWER"GND";
"A"24;
%"Q_CAP"
"1","(550,275)","0","pure_quanta","I90";
;
PART_NUMBER"CH5104KEB02"
VALUE"1UF"
PACK_TYPE"C0402"
TOLERANCE"10%"
MATERIAL"X6S"
VOLTAGE"25V"
LOCATION"C1561"
CDS_LIB"pure_quanta"
$SEC"1"
CDS_SEC"1";
"B"
$PN"2"28;
"A"
$PN"1"35;
%"Q_CAP"
"1","(0,4100)","0","pure_quanta","I91";
;
PART_NUMBER"CH5104KEB02"
PACK_TYPE"C0402"
TOLERANCE"10%"
VALUE"1UF"
VOLTAGE"25V"
MATERIAL"EMPTY"
LOCATION"C4562"
CDS_LIB"pure_quanta"
$SEC"1"
CDS_SEC"1";
"B"
$PN"2"27;
"A"
$PN"1"51;
%"Q_CAP"
"1","(400,4100)","0","pure_quanta","I92";
;
PART_NUMBER"CH4104K1B00"
TOLERANCE"10%"
PACK_TYPE"0402"
MATERIAL"EMPTY"
VALUE"0.1UF"
VOLTAGE"25V"
$LOCATION"C2393"
CDS_LIB"pure_quanta"
CDS_LOCATION"C2393"
$SEC"1"
CDS_SEC"1";
"B"
$PN"2"27;
"A"
$PN"1"51;
%"Q_CAP"
"1","(950,275)","0","pure_quanta","I93";
;
PART_NUMBER"CH4104K1B00"
VOLTAGE"25V"
MATERIAL"X7R"
VALUE"0.1UF"
TOLERANCE"10%"
PACK_TYPE"0402"
$LOCATION"C2394"
CDS_LIB"pure_quanta"
CDS_LOCATION"C2394"
$SEC"1"
CDS_SEC"1";
"B"
$PN"2"29;
"A"
$PN"1"35;
%"UNIVERSAL_GND"
"1","(950,25)","0","logical_power","I94";
;
CDS_LIB"logical_power"
HDL_POWER"GND";
"A"29;
%"Q_CAP"
"1","(-1625,-1025)","0","pure_quanta","I95";
;
PART_NUMBER"CH4104K1B00"
VALUE"0.1UF"
VOLTAGE"25V"
PACK_TYPE"0402"
TOLERANCE"10%"
MATERIAL"EMPTY"
$LOCATION"C2392"
CDS_LIB"pure_quanta"
CDS_LOCATION"C2392"
$SEC"1"
CDS_SEC"1";
"B"
$PN"2"31;
"A"
$PN"1"41;
%"UNIVERSAL_GND"
"1","(-1625,-1250)","0","logical_power","I96";
;
CDS_LIB"logical_power"
HDL_POWER"GND";
"A"31;
%"Q_RES"
"2","(-1300,-675)","0","pure_quanta","I97";
;
PART_NUMBER"CS21002FB06"
TOLERANCE"1%"
WATTAGE"1/16W"
VALUE"1K"
MATERIAL"EMPTY"
PACK_TYPE"0402LF"
LOCATION"R4804"
CDS_LIB"pure_quanta"
$SEC"1"
CDS_SEC"1";
"A"
$PN"1"4;
"B"
$PN"2"41;
%"Q_RES"
"2","(1275,675)","0","pure_quanta","I98";
;
PART_NUMBER"CS21002FB06"
TOLERANCE"1%"
VALUE"1K"
MATERIAL"CHIP"
PACK_TYPE"0402LF"
WATTAGE"1/16W"
LOCATION"R4806"
CDS_LIB"pure_quanta"
$SEC"1"
CDS_SEC"1";
"A"
$PN"1"32;
"B"
$PN"2"35;
%"Q_RES"
"2","(650,4450)","0","pure_quanta","I99";
;
PART_NUMBER"CS21002FB06"
PACK_TYPE"0402LF"
VALUE"1K"
TOLERANCE"1%"
WATTAGE"1/16W"
MATERIAL"EMPTY"
LOCATION"R4805"
CDS_LIB"pure_quanta"
$SEC"1"
CDS_SEC"1";
"A"
$PN"1"9;
"B"
$PN"2"51;
END.
